;LEADER: 12 
;HEADER: 
;CODE  : ASCII 
;FILE  : 9127_F0T_Expander_BD_F_v02_0110_1240-bd-18-9.drl for backdrilling ... from layer BOTTOM to layer GND3
;DESIGN: 9127_F0T_Expander_BD_F_v02_0110_1240.brd
;MUST-NOT-CUT-LAYER = IN2,  MAX_DRILL_DEPTH = 69.45 MILS,  MFG_STUB_LENGTH = 0.00 MILS
;   BackdrillSize 1. = 15.700000 Tolerance = +0.000000/-0.000000 NON_PLATED MILS Quantity = 384
;   BackdrillSize 2. = 17.700000 Tolerance = +0.000000/-0.000000 NON_PLATED MILS Quantity = 648
;   BackdrillSize 3. = 19.900000 Tolerance = +0.000000/-0.000000 NON_PLATED MILS Quantity = 256
%
G90
X0152559Y1232283
X0152559Y1236023
X0145078Y1239763
X0160039Y1232283
X0148818Y1239763
X0167519Y1236023
X0163779Y1228543
X0148818Y1228543
X0156299Y1228543
X0167519Y1232283
X0156299Y1224803
X0163779Y1224803
X0145078Y1228543
X0160039Y1236023
X0167519Y1202362
X0167519Y1217322
X0163779Y1217322
X0167519Y1194881
X0163779Y1202362
X0167519Y1187401
X0163779Y1209842
X0163779Y1194881
X0167519Y1209842
X0163779Y1187401
X0223622Y1086417
X0204921Y1078936
X0208661Y1086417
X0201181Y1086417
X0178740Y1086417
X0197440Y1075196
X0216141Y1082677
X0197440Y1078936
X0227362Y1078936
X0212401Y1075196
X0201181Y1082677
X0223622Y1082677
X0231102Y1086417
X0231102Y1082677
X0216141Y1086417
X0182480Y1075196
X0193700Y1082677
X0174999Y1075196
X0178740Y1082677
X0193700Y1086417
X0208661Y1082677
X0189960Y1078936
X0182480Y1078936
X0212401Y1078936
X0219881Y1075196
X0174999Y1078936
X0204921Y1075196
X0227362Y1075196
X0219881Y1078936
X0186220Y1086417
X0186220Y1082677
X0189960Y1075196
X0174999Y1213582
X0174999Y1206102
X0171259Y1191141
X0171259Y1198621
X0174999Y1191141
X0171259Y1206102
X0171259Y1213582
X0174999Y1198621
X0264763Y1236023
X0234842Y1236023
X0249803Y1236023
X0253543Y1224803
X0268503Y1228543
X0261023Y1228543
X0246062Y1224803
X0234842Y1232283
X0257283Y1236023
X0257283Y1232283
X0246062Y1228543
X0249803Y1232283
X0242322Y1232283
X0231102Y1224803
X0242322Y1236023
X0253543Y1228543
X0261023Y1224803
X0231102Y1228543
X0268503Y1224803
X0238582Y1228543
X0238582Y1224803
X0264763Y1232283
X0287204Y1236023
X0283464Y1228543
X0272244Y1232283
X0275984Y1228543
X0283464Y1224803
X0287204Y1232283
X0279724Y1236023
X0279724Y1232283
X0272244Y1236023
X0275984Y1224803
X0658268Y1086417
X0635827Y1082677
X0665748Y1086417
X0650787Y1086417
X0647047Y1075196
X0654527Y1078936
X0635827Y1086417
X0658268Y1082677
X0632086Y1075196
X0654527Y1075196
X0650787Y1082677
X0639567Y1078936
X0647047Y1078936
X0665748Y1082677
X0643307Y1082677
X0643307Y1086417
X0632086Y1078936
X0639567Y1075196
X0662008Y1078936
X0662008Y1075196
X0658268Y1228543
X0665748Y1228543
X0658268Y1224803
X0662008Y1236023
X0665748Y1224803
X0662008Y1232283
X0755512Y1224803
X0759252Y1236023
X0762992Y1224803
X0748031Y1228543
X0759252Y1232283
X0766732Y1236023
X0766732Y1232283
X0751772Y1232283
X0762992Y1228543
X0751772Y1236023
X0755512Y1228543
X0748031Y1224803
X0706890Y1232283
X0710630Y1224803
X0695669Y1224803
X0703149Y1224803
X0714370Y1232283
X0695669Y1228543
X0691929Y1232283
X0699409Y1236023
X0680709Y1228543
X0669488Y1236023
X0688189Y1224803
X0673228Y1224803
X0676968Y1232283
X0684449Y1236023
X0680709Y1224803
X0673228Y1228543
X0684449Y1232283
X0676968Y1236023
X0669488Y1232283
X0703149Y1228543
X0699409Y1232283
X0710630Y1228543
X0691929Y1236023
X0714370Y1236023
X0688189Y1228543
X0706890Y1236023
X0755512Y1206102
X0759252Y1209842
X0751772Y1198621
X0759252Y1217322
X0759252Y1202362
X0751772Y1206102
X0755512Y1198621
X0755512Y1213582
X0762992Y1209842
X0751772Y1213582
X0762992Y1217322
X0762992Y1202362
X0669488Y1075196
X0669488Y1078936
X0680709Y1082677
X0673228Y1082677
X0673228Y1086417
X0684449Y1078936
X0680709Y1086417
X0684449Y1075196
X0688189Y1082677
X0688189Y1086417
X0676968Y1075196
X0676968Y1078936
X0781693Y1239763
X0774212Y1236023
X0777953Y1239763
X0774212Y1232283
X0777953Y1228543
X0770472Y1224803
X0781693Y1228543
X0770472Y1228543
X1062991Y1228543
X1062991Y1239763
X1066732Y1232283
X1059251Y1239763
X1066732Y1236023
X1059251Y1228543
X1167716Y1228543
X1152755Y1224803
X1145275Y1228543
X1070472Y1224803
X1077952Y1228543
X1074212Y1232283
X1077952Y1224803
X1074212Y1236023
X1081692Y1236023
X1081692Y1232283
X1070472Y1228543
X1156495Y1236023
X1163976Y1236023
X1156495Y1232283
X1145275Y1224803
X1152755Y1228543
X1149015Y1232283
X1149015Y1236023
X1160235Y1228543
X1167716Y1224803
X1163976Y1232283
X1160235Y1224803
X1085432Y1213582
X1085432Y1191141
X1085432Y1206102
X1081692Y1187401
X1077952Y1217322
X1089172Y1213582
X1081692Y1217322
X1081692Y1194881
X1085432Y1198621
X1081692Y1209842
X1081692Y1202362
X1077952Y1187401
X1077952Y1209842
X1089172Y1198621
X1089172Y1191141
X1089172Y1206102
X1077952Y1202362
X1077952Y1194881
X1096653Y1078936
X1137795Y1082677
X1141535Y1078936
X1137795Y1086417
X1134054Y1075196
X1130314Y1082677
X1130314Y1086417
X1122834Y1082677
X1119094Y1075196
X1089172Y1078936
X1126574Y1078936
X1145275Y1082677
X1092913Y1086417
X1115354Y1086417
X1141535Y1075196
X1134054Y1078936
X1100393Y1086417
X1111613Y1078936
X1092913Y1082677
X1089172Y1075196
X1115354Y1082677
X1126574Y1075196
X1104133Y1075196
X1119094Y1078936
X1107873Y1086417
X1096653Y1075196
X1107873Y1082677
X1104133Y1078936
X1122834Y1086417
X1145275Y1086417
X1111613Y1075196
X1100393Y1082677
X1171456Y1236023
X1201377Y1232283
X1197637Y1228543
X1193897Y1232283
X1190157Y1224803
X1201377Y1236023
X1175196Y1224803
X1190157Y1228543
X1193897Y1236023
X1171456Y1232283
X1182676Y1224803
X1197637Y1224803
X1178936Y1232283
X1175196Y1228543
X1186417Y1232283
X1178936Y1236023
X1186417Y1236023
X1182676Y1228543
X1561220Y1075196
X1557480Y1086417
X1568700Y1075196
X1553740Y1075196
X1550000Y1082677
X1564960Y1086417
X1564960Y1082677
X1550000Y1086417
X1561220Y1078936
X1553740Y1078936
X1557480Y1082677
X1546259Y1078936
X1546259Y1075196
X1568700Y1078936
X1576181Y1078936
X1598622Y1078936
X1576181Y1075196
X1591141Y1078936
X1587401Y1086417
X1572441Y1082677
X1579921Y1086417
X1587401Y1082677
X1594882Y1086417
X1583661Y1078936
X1579921Y1082677
X1591141Y1075196
X1598622Y1075196
X1594882Y1082677
X1602362Y1086417
X1602362Y1082677
X1583661Y1075196
X1572441Y1086417
X1665945Y1198621
X1665945Y1213582
X1665945Y1206102
X1662204Y1224803
X1665945Y1236023
X1665945Y1232283
X1662204Y1228543
X1591141Y1236023
X1576181Y1232283
X1587401Y1224803
X1587401Y1228543
X1598622Y1232283
X1579921Y1224803
X1572441Y1224803
X1602362Y1228543
X1613582Y1232283
X1624803Y1228543
X1609842Y1224803
X1621063Y1232283
X1602362Y1224803
X1606102Y1232283
X1609842Y1228543
X1613582Y1236023
X1621063Y1236023
X1606102Y1236023
X1628543Y1232283
X1617322Y1224803
X1628543Y1236023
X1624803Y1224803
X1617322Y1228543
X1576181Y1236023
X1594882Y1228543
X1583661Y1232283
X1579921Y1228543
X1583661Y1236023
X1591141Y1232283
X1598622Y1236023
X1572441Y1228543
X1594882Y1224803
X1688385Y1236023
X1669685Y1224803
X1688385Y1232283
X1677165Y1224803
X1684645Y1228543
X1684645Y1224803
X1695866Y1228543
X1692126Y1228543
X1680905Y1232283
X1680905Y1236023
X1673425Y1232283
X1669685Y1228543
X1692126Y1239763
X1677165Y1228543
X1695866Y1239763
X1673425Y1236023
X1673425Y1217322
X1669685Y1198621
X1677165Y1202362
X1669685Y1206102
X1673425Y1209842
X1669685Y1213582
X1673425Y1202362
X1677165Y1217322
X1677165Y1209842
M00
X0028388Y0118342
X0028388Y0121742
X0035688Y0114655
X0035688Y0111255
X0035688Y0128828
X0028388Y0132515
X0035688Y0125428
X0028388Y0135915
X0140712Y1360099
X0137312Y1360099
X0103992Y1384297
X0088352Y1408495
X0091752Y1408495
X0088352Y1360099
X0091752Y1360099
X0079512Y1384297
X0161792Y1396583
X0076112Y1384297
X0165192Y1396583
X0161792Y1348187
X0112832Y1348187
X0165192Y1348187
X0137312Y1348187
X0137312Y1396583
X0140712Y1396583
X0152952Y1372385
X0112832Y1396583
X0091752Y1348187
X0103992Y1372385
X0088352Y1396583
X0088352Y1348187
X0116232Y1396583
X0116232Y1348187
X0076112Y1372385
X0128472Y1372385
X0140712Y1348187
X0149552Y1372385
X0100592Y1372385
X0091752Y1396583
X0125072Y1372385
X0079512Y1372385
X0116232Y1360099
X0116232Y1408495
X0112832Y1408495
X0128472Y1384297
X0125072Y1384297
X0112832Y1360099
X0100592Y1384297
X0149552Y1384297
X0137312Y1408495
X0161792Y1408495
X0161792Y1360099
X0165192Y1408495
X0140712Y1408495
X0165192Y1360099
X0152952Y1384297
X0138050Y0125428
X0138050Y0128828
X0130750Y0135915
X0130750Y0132515
X0138050Y0114655
X0130750Y0118342
X0130750Y0121742
X0138050Y0111255
X0240412Y0111255
X0233112Y0118342
X0240412Y0114655
X0233112Y0121742
X0233112Y0135915
X0240412Y0128828
X0240412Y0125428
X0233112Y0132515
X0257263Y1348187
X0186272Y1348187
X0201912Y1372385
X0189672Y1396583
X0245023Y1384297
X0177432Y1372385
X0198512Y1372385
X0241623Y1384297
X0257263Y1360099
X0174032Y1372385
X0253863Y1360099
X0186272Y1396583
X0189672Y1348187
X0266103Y1384297
X0253863Y1348187
X0253863Y1408495
X0257263Y1408495
X0174032Y1384297
X0266103Y1372385
X0186272Y1408495
X0201912Y1384297
X0241623Y1372385
X0189672Y1408495
X0186272Y1360099
X0198512Y1384297
X0177432Y1384297
X0189672Y1360099
X0245023Y1372385
X0257263Y1396583
X0253863Y1396583
X0318463Y1372385
X0281743Y1396583
X0367423Y1372385
X0355183Y1396583
X0290583Y1372385
X0330703Y1348187
X0306223Y1396583
X0351783Y1360099
X0339543Y1384297
X0342943Y1384297
X0355183Y1408495
X0364023Y1384297
X0351783Y1408495
X0367423Y1384297
X0355183Y1360099
X0302823Y1360099
X0306223Y1360099
X0278343Y1408495
X0293983Y1384297
X0281743Y1408495
X0278343Y1360099
X0290583Y1384297
X0281743Y1360099
X0269503Y1384297
X0327303Y1360099
X0327303Y1408495
X0330703Y1408495
X0306223Y1408495
X0315063Y1384297
X0302823Y1408495
X0327303Y1396583
X0318463Y1384297
X0342943Y1372385
X0330703Y1360099
X0278343Y1348187
X0351783Y1396583
X0306223Y1348187
X0364023Y1372385
X0355183Y1348187
X0302823Y1348187
X0281743Y1348187
X0351783Y1348187
X0278343Y1396583
X0330703Y1396583
X0339543Y1372385
X0269503Y1372385
X0293983Y1372385
X0302823Y1396583
X0327303Y1348187
X0315063Y1372385
X0342774Y0128828
X0342774Y0125428
X0335474Y0132515
X0335474Y0135915
X0335474Y0121742
X0342774Y0114655
X0342774Y0111255
X0335474Y0118342
X0468282Y1384297
X0452642Y1360099
X0456042Y1408495
X0443802Y1384297
X0440402Y1384297
X0464882Y1384297
X0456042Y1360099
X0452642Y1408495
X0468282Y1372385
X0443802Y1372385
X0456042Y1396583
X0440402Y1372385
X0456042Y1348187
X0452642Y1396583
X0452642Y1348187
X0464882Y1372385
X0513842Y1384297
X0526082Y1360099
X0517242Y1384297
X0529482Y1360099
X0480522Y1408495
X0492762Y1384297
X0489362Y1384297
X0505002Y1360099
X0477122Y1360099
X0501602Y1360099
X0480522Y1360099
X0477122Y1408495
X0550562Y1348187
X0550562Y1396583
X0526082Y1348187
X0538322Y1372385
X0562802Y1372385
X0529482Y1348187
X0513842Y1372385
X0529482Y1396583
X0492762Y1372385
X0501602Y1396583
X0477122Y1348187
X0477122Y1396583
X0505002Y1348187
X0489362Y1372385
X0480522Y1348187
X0501602Y1348187
X0480522Y1396583
X0550562Y1360099
X0550562Y1408495
X0562802Y1384297
X0553962Y1360099
X0541722Y1384297
X0553962Y1408495
X0566202Y1384297
X0538322Y1384297
X0526082Y1408495
X0501602Y1408495
X0529482Y1408495
X0505002Y1408495
X0541722Y1372385
X0526082Y1396583
X0553962Y1396583
X0517242Y1372385
X0566202Y1372385
X0505002Y1396583
X0553962Y1348187
X0492775Y0125428
X0492775Y0128828
X0485475Y0132515
X0485475Y0135915
X0485475Y0121742
X0492775Y0111255
X0492775Y0114655
X0485475Y0118342
X0595137Y0114655
X0587837Y0121742
X0595137Y0111255
X0587837Y0118342
X0595137Y0128828
X0587837Y0132515
X0595137Y0125428
X0587837Y0135915
X0666408Y1384297
X0654168Y1408495
X0663008Y1384297
X0650768Y1408495
X0650768Y1360099
X0641928Y1384297
X0638528Y1384297
X0654168Y1360099
X0650768Y1396583
X0666408Y1372385
X0641928Y1372385
X0663008Y1372385
X0650768Y1348187
X0654168Y1348187
X0654168Y1396583
X0638528Y1372385
X0727608Y1408401
X0703128Y1408495
X0711968Y1384297
X0690888Y1384297
X0675248Y1408495
X0727608Y1360099
X0736448Y1384297
X0760928Y1384297
X0675248Y1360099
X0715368Y1384297
X0739848Y1384297
X0724208Y1360099
X0678648Y1360099
X0687488Y1384297
X0748688Y1360099
X0678648Y1408495
X0699728Y1360099
X0724208Y1408401
X0699728Y1408495
X0703128Y1360099
X0764328Y1384297
X0752088Y1360099
X0752088Y1348187
X0736448Y1372385
X0703128Y1396583
X0724208Y1348187
X0675248Y1348187
X0760928Y1372385
X0678648Y1396583
X0703128Y1348187
X0748688Y1348187
X0699728Y1396583
X0675248Y1396583
X0678648Y1348187
X0699728Y1348187
X0711968Y1372385
X0727608Y1396489
X0739848Y1372385
X0687488Y1372385
X0724208Y1396489
X0727608Y1348187
X0715368Y1372385
X0764328Y1372385
X0690888Y1372385
X0697499Y0128828
X0697499Y0125428
X0690199Y0135915
X0690199Y0132515
X0690199Y0118342
X0690199Y0121742
X0697499Y0111255
X0697499Y0114655
X0792561Y0121742
X0792561Y0118342
X0799861Y0111255
X0799861Y0114655
X0799861Y0125428
X0799861Y0128828
X0792561Y0132515
X0792561Y0135915
X0776568Y1360099
X0773168Y1360099
X0773168Y1348187
X0776568Y1348187
X0942561Y0135915
X0949861Y0128828
X0949861Y0125428
X0942561Y0132515
X0942561Y0121742
X0949861Y0114655
X0942561Y0118342
X0949861Y0111255
X1052223Y0114655
X1044923Y0121742
X1052223Y0111255
X1044923Y0118342
X1044923Y0132515
X1052223Y0128828
X1052223Y0125428
X1044923Y0135915
X1058113Y1384297
X1054713Y1384297
X1066953Y1408495
X1066953Y1360099
X1054713Y1372385
X1066953Y1396583
X1058113Y1372385
X1066953Y1348187
X1070353Y1408495
X1070353Y1360099
X1079193Y1384297
X1094833Y1360099
X1094833Y1408495
X1103673Y1384297
X1091433Y1408495
X1119313Y1360099
X1082593Y1384297
X1115913Y1360099
X1091433Y1360099
X1107073Y1384297
X1131553Y1372385
X1119313Y1348187
X1070353Y1348187
X1094833Y1396583
X1152633Y1372385
X1119313Y1396583
X1115913Y1348187
X1168273Y1396583
X1115913Y1396583
X1164873Y1348187
X1164873Y1396583
X1082593Y1372385
X1168273Y1348187
X1103673Y1372385
X1091433Y1348187
X1107073Y1372385
X1079193Y1372385
X1143793Y1348187
X1140393Y1396583
X1140393Y1348187
X1091433Y1396583
X1094833Y1348187
X1143793Y1396583
X1070353Y1396583
X1128153Y1372385
X1156033Y1372385
X1119313Y1408495
X1140393Y1408495
X1168273Y1360099
X1164873Y1408495
X1152633Y1384297
X1168273Y1408495
X1143793Y1360099
X1131553Y1384297
X1115913Y1408495
X1164873Y1360099
X1140393Y1360099
X1156033Y1384297
X1128153Y1384297
X1143793Y1408495
X1154585Y0125428
X1147285Y0132515
X1147285Y0135915
X1154585Y0128828
X1154585Y0111255
X1154585Y0114655
X1147285Y0121742
X1147285Y0118342
X1249647Y0121742
X1256947Y0111255
X1249647Y0118342
X1256947Y0114655
X1256947Y0125428
X1256947Y0128828
X1249647Y0132515
X1249647Y0135915
X1245966Y1408495
X1242566Y1408495
X1258206Y1384297
X1254806Y1384297
X1267046Y1360099
X1245966Y1360099
X1267046Y1408495
X1233726Y1384297
X1242566Y1360099
X1230326Y1384297
X1242566Y1396583
X1233726Y1372385
X1180513Y1372385
X1177113Y1372385
X1180513Y1384297
X1258206Y1372385
X1177113Y1384297
X1254806Y1372385
X1230326Y1372385
X1245966Y1396583
X1242566Y1348187
X1245966Y1348187
X1267046Y1396583
X1267046Y1348187
X1279286Y1384297
X1282686Y1384297
X1294926Y1360099
X1270446Y1360099
X1270446Y1408495
X1291526Y1360099
X1282686Y1372385
X1294926Y1348187
X1352726Y1372385
X1328246Y1384297
X1307166Y1384297
X1356126Y1384297
X1319406Y1408495
X1316006Y1408495
X1294926Y1408495
X1340486Y1408495
X1316006Y1360099
X1291526Y1408495
X1340486Y1360099
X1343886Y1408495
X1343886Y1396583
X1340486Y1348187
X1328246Y1372385
X1356126Y1372385
X1270446Y1396583
X1291526Y1396583
X1331646Y1372385
X1319406Y1360099
X1343886Y1348187
X1343886Y1360099
X1303766Y1384297
X1352726Y1384297
X1291526Y1348187
X1331646Y1384297
X1316006Y1348187
X1270446Y1348187
X1340486Y1396583
X1303766Y1372385
X1294926Y1396583
X1316006Y1396583
X1279286Y1372385
X1307166Y1372385
X1319406Y1396583
X1319406Y1348187
X1297687Y-0030256
X1297687Y-0033656
X1337687Y-0072706
X1337687Y-0069306
X1406948Y0114655
X1399648Y0118342
X1399648Y0121742
X1406948Y0111255
X1406948Y0125428
X1406948Y0128828
X1399648Y0135915
X1399648Y0132515
X1461370Y1384297
X1464770Y1384297
X1461370Y1372385
X1464770Y1372385
X1547050Y1360099
X1550450Y1360099
X1547050Y1408495
X1522570Y1408495
X1538210Y1384297
X1550450Y1408495
X1525970Y1408495
X1559290Y1384297
X1534810Y1384297
X1562690Y1384297
X1501490Y1408495
X1477010Y1360099
X1489250Y1384297
X1477010Y1408495
X1510330Y1384297
X1513730Y1384297
X1498090Y1360099
X1501490Y1360099
X1473610Y1408495
X1485850Y1384297
X1473610Y1360099
X1498090Y1408495
X1525970Y1360099
X1522570Y1360099
X1501490Y1396583
X1473610Y1348187
X1498090Y1348187
X1501490Y1348187
X1522570Y1348187
X1473610Y1396583
X1525970Y1396583
X1547050Y1396583
X1547050Y1348187
X1522570Y1396583
X1534810Y1372385
X1550450Y1348187
X1550450Y1396583
X1538210Y1372385
X1559290Y1372385
X1562690Y1372385
X1477010Y1348187
X1513730Y1372385
X1485850Y1372385
X1477010Y1396583
X1489250Y1372385
X1498090Y1396583
X1525970Y1348187
X1510330Y1372385
X1502010Y0132515
X1509310Y0128828
X1509310Y0125428
X1502010Y0135915
X1502010Y0118342
X1509310Y0111255
X1509310Y0114655
X1502010Y0121742
X1517261Y-0030358
X1517261Y-0033758
X1481905Y-0072678
X1481905Y-0069278
X1611672Y0114655
X1611672Y0111255
X1604372Y0121742
X1604372Y0118342
X1604372Y0135915
X1604372Y0132515
X1611672Y0128828
X1611672Y0125428
X1623638Y1396583
X1648118Y1348187
X1663758Y1372385
X1660358Y1372385
X1611398Y1372385
X1648118Y1396583
X1651518Y1396583
X1660358Y1384297
X1627038Y1348187
X1614798Y1384297
X1651518Y1408495
X1623638Y1348187
X1635878Y1372385
X1627038Y1396583
X1614798Y1372385
X1648118Y1408495
X1651518Y1348187
X1648118Y1360099
X1639278Y1372385
X1639278Y1384297
X1627038Y1360099
X1623638Y1408495
X1635878Y1384297
X1651518Y1360099
X1663758Y1384297
X1623638Y1360099
X1627038Y1408495
X1611398Y1384297
X1587170Y1384297
X1571530Y1360099
X1574930Y1408495
X1574930Y1360099
X1571530Y1408495
X1583770Y1384297
X1574930Y1396583
X1571530Y1348187
X1574930Y1348187
X1583770Y1372385
X1587170Y1372385
X1571530Y1396583
X1697078Y1348187
X1675998Y1348187
X1672598Y1348187
X1737198Y1372385
X1688238Y1372385
X1733798Y1372385
X1684838Y1372385
X1697078Y1396583
X1724958Y1396583
X1724958Y1348187
X1709318Y1372385
X1672598Y1360099
X1700478Y1408495
X1700478Y1396583
X1721558Y1396583
X1724958Y1408495
X1721558Y1360099
X1700478Y1348187
X1672598Y1396583
X1700478Y1360099
X1721558Y1348187
X1721558Y1408495
X1672598Y1408495
X1712718Y1384297
X1712718Y1372385
X1675998Y1360099
X1675998Y1396583
X1709318Y1384297
X1733798Y1384297
X1697078Y1408495
X1737198Y1384297
X1688238Y1384297
X1684838Y1384297
X1697078Y1360099
X1724958Y1360099
X1675998Y1408495
X1706734Y0135915
X1714034Y0128828
X1706734Y0132515
X1714034Y0125428
X1706734Y0121742
X1706734Y0118342
X1714034Y0114655
X1714034Y0111255
M00
X0118543Y1585788
X0109882Y1581457
X0118543Y1580670
X0109882Y1576339
X0135866Y1585788
X0127205Y1581457
X0135866Y1580670
X0127205Y1576339
X0153189Y1585788
X0144528Y1581457
X0153189Y1580670
X0144528Y1576339
X0161850Y1581457
X0161850Y1576339
X0118543Y1483426
X0109882Y1479095
X0118543Y1478308
X0109882Y1473977
X0135866Y1483426
X0127205Y1479095
X0135866Y1478308
X0127205Y1473977
X0153189Y1483426
X0144528Y1479095
X0153189Y1478308
X0144528Y1473977
X0161850Y1479095
X0161850Y1473977
X0170512Y1483426
X0170512Y1478308
X0170512Y1585788
X0170512Y1580670
X0291771Y1601142
X0283110Y1596811
X0291771Y1596024
X0283110Y1591693
X0309094Y1601142
X0300433Y1596811
X0309094Y1596024
X0300433Y1591693
X0326417Y1601142
X0317756Y1596811
X0326417Y1596024
X0317756Y1591693
X0343740Y1601142
X0335078Y1596811
X0343740Y1596024
X0335078Y1591693
X0291771Y1498780
X0283110Y1494449
X0291771Y1493662
X0283110Y1489331
X0309094Y1498780
X0300433Y1494449
X0309094Y1493662
X0300433Y1489331
X0326417Y1498780
X0317756Y1494449
X0326417Y1493662
X0317756Y1489331
X0343740Y1498780
X0335078Y1494449
X0343740Y1493662
X0335078Y1489331
X0465000Y1514134
X0456339Y1509804
X0465000Y1509016
X0456339Y1504685
X0465000Y1601142
X0456339Y1596811
X0465000Y1596024
X0456339Y1591693
X0482323Y1601142
X0473662Y1596811
X0482323Y1596024
X0473662Y1591693
X0499646Y1601142
X0490985Y1596811
X0499646Y1596024
X0490985Y1591693
X0516969Y1601142
X0508307Y1596811
X0516969Y1596024
X0508307Y1591693
X0482323Y1514134
X0473662Y1509804
X0482323Y1509016
X0473662Y1504685
X0499646Y1514134
X0490985Y1509804
X0499646Y1509016
X0490985Y1504685
X0516969Y1514134
X0508307Y1509804
X0516969Y1509016
X0508307Y1504685
X0638228Y1468071
X0629567Y1463741
X0638228Y1462953
X0629567Y1458622
X0655551Y1468071
X0646890Y1463741
X0655551Y1462953
X0646890Y1458622
X0664213Y1463741
X0664213Y1458622
X0638228Y1570434
X0629567Y1566103
X0638228Y1565315
X0629567Y1560985
X0655551Y1570434
X0646890Y1566103
X0655551Y1565315
X0646890Y1560985
X0664213Y1566103
X0664213Y1560985
X0672874Y1570434
X0672874Y1565315
X0690197Y1570434
X0681535Y1566103
X0690197Y1565315
X0681535Y1560985
X0672874Y1468071
X0672874Y1462953
X0690197Y1468071
X0681535Y1463741
X0690197Y1462953
X0681535Y1458622
X1140511Y1585788
X1131850Y1581457
X1140511Y1580670
X1131850Y1576339
X1157834Y1585788
X1149173Y1581457
X1157834Y1580670
X1149173Y1576339
X1166496Y1581457
X1166496Y1576339
X1140511Y1483426
X1131850Y1479095
X1140511Y1478308
X1131850Y1473977
X1157834Y1483426
X1149173Y1479095
X1157834Y1478308
X1149173Y1473977
X1166496Y1479095
X1166496Y1473977
X1175157Y1483426
X1175157Y1478308
X1192480Y1483426
X1183818Y1479095
X1192480Y1478308
X1183818Y1473977
X1175157Y1585788
X1175157Y1580670
X1192480Y1585788
X1183818Y1581457
X1192480Y1580670
X1183818Y1576339
X1313740Y1601142
X1305079Y1596811
X1313740Y1596024
X1305079Y1591693
X1331063Y1601142
X1322402Y1596811
X1331063Y1596024
X1322402Y1591693
X1348386Y1601142
X1339725Y1596811
X1348386Y1596024
X1339725Y1591693
X1365709Y1601142
X1357047Y1596811
X1365709Y1596024
X1357047Y1591693
X1313740Y1498780
X1305079Y1494449
X1313740Y1493662
X1305079Y1489331
X1331063Y1498780
X1322402Y1494449
X1331063Y1493662
X1322402Y1489331
X1348386Y1498780
X1339725Y1494449
X1348386Y1493662
X1339725Y1489331
X1365709Y1498780
X1357047Y1494449
X1365709Y1493662
X1357047Y1489331
X1486968Y1601142
X1478307Y1596811
X1486968Y1596024
X1478307Y1591693
X1504291Y1601142
X1495630Y1596811
X1504291Y1596024
X1495630Y1591693
X1521614Y1601142
X1512953Y1596811
X1521614Y1596024
X1512953Y1591693
X1538937Y1601142
X1530275Y1596811
X1538937Y1596024
X1530275Y1591693
X1486968Y1514134
X1478307Y1509804
X1486968Y1509016
X1478307Y1504685
X1504291Y1514134
X1495630Y1509804
X1504291Y1509016
X1495630Y1504685
X1521614Y1514134
X1512953Y1509804
X1521614Y1509016
X1512953Y1504685
X1538937Y1514134
X1530275Y1509804
X1538937Y1509016
X1530275Y1504685
X1660196Y1468071
X1651535Y1463741
X1660196Y1462953
X1651535Y1458622
X1668858Y1463741
X1668858Y1458622
X1660196Y1570434
X1651535Y1566103
X1660196Y1565315
X1651535Y1560985
X1668858Y1566103
X1668858Y1560985
X1677519Y1570434
X1677519Y1565315
X1694842Y1570434
X1686181Y1566103
X1694842Y1565315
X1686181Y1560985
X1712165Y1570434
X1703503Y1566103
X1712165Y1565315
X1703503Y1560985
X1677519Y1468071
X1677519Y1462953
X1694842Y1468071
X1686181Y1463741
X1694842Y1462953
X1686181Y1458622
X1712165Y1468071
X1703503Y1463741
X1712165Y1462953
X1703503Y1458622
M30
